# T6G (Grand Teton) — schematic netlist excerpt (pin names and nets, part order shuffled) for the footprints in the layout excerpt that follows; sources: Cadence DE-HDL packaged netlist, KiCad conversion of 04192023_DAF0TMB3IC0_F0TG_MB_C_brd_V02_OCP.brd

C2328  Q_CAP  10UF 6.3V 20% X6S  pkg C0402  page 182 : A = P3V3_9ZXL045_P0_VDD ; B = GND
R1149  Q_RES  1K 1% CHIP  pkg 0402LF  page 142 : A = P3V3_AUX ; B = HP_LVC3_OCP_V3_2_PRSNT2

(kicad_pcb
	(version 20260206)
	(generator "pcbnew")
	(generator_version "10.0")
	(general
		(thickness 1.6)
		(legacy_teardrops no)
	)
	(paper "A4")
	(title_block
		(title "04192023_DAF0TMB3IC0_F0TG_MB_C_brd_V02_OCP.brd")
		(comment 1 "Grand Teton / footprints 216-217 of 8354")
	)
	(layers
		(0 "F.Cu" signal "TOP")
		(4 "In1.Cu" signal "GND")
		(6 "In2.Cu" signal "IN1")
		(8 "In3.Cu" signal "GND1")
		(10 "In4.Cu" signal "IN2")
		(12 "In5.Cu" signal "GND2")
		(14 "In6.Cu" signal "IN3")
		(16 "In7.Cu" signal "GND3")
		(18 "In8.Cu" signal "VCC")
		(20 "In9.Cu" signal "VCC1")
		(22 "In10.Cu" signal "GND4")
		(24 "In11.Cu" signal "IN4")
		(26 "In12.Cu" signal "GND5")
		(28 "In13.Cu" signal "IN5")
		(30 "In14.Cu" signal "GND6")
		(32 "In15.Cu" signal "IN6")
		(34 "In16.Cu" signal "GND7")
		(2 "B.Cu" signal "BOTTOM")
		(9 "F.Adhes" user "F.Adhesive")
		(11 "B.Adhes" user "B.Adhesive")
		(13 "F.Paste" user "Package Geometry/Pastemask Top")
		(15 "B.Paste" user "Package Geometry/Pastemask Bottom")
		(5 "F.SilkS" user "Ref Des/Silkscreen Top")
		(7 "B.SilkS" user "Ref Des/Silkscreen Bottom")
		(1 "F.Mask" user "Board Geometry/Soldermask Top")
		(3 "B.Mask" user "Board Geometry/Soldermask Bottom")
		(17 "Dwgs.User" user "User.Drawings")
		(19 "Cmts.User" user "User.Comments")
		(21 "Eco1.User" user "User.Eco1")
		(23 "Eco2.User" user "User.Eco2")
		(25 "Edge.Cuts" user "Board Geometry/Outline")
		(27 "Margin" user)
		(31 "F.CrtYd" user "Package Geometry/Place Bound Top")
		(29 "B.CrtYd" user "Package Geometry/Place Bound Bottom")
		(35 "F.Fab" user "Ref Des/Assembly Top")
		(33 "B.Fab" user "Ref Des/Assembly Bottom")
	)
	(footprint ""
		(layer "F.Cu")
		(at 49.657 -37.846)
		(property "Reference" "R1149"
			(at 0 0 0)
			(layer "F.SilkS")
			(hide yes)
			(effects
				(font
					(size 1.27 1.27)
				)
			)
		)
		(property "Value" ""
			(at 0 0 0)
			(layer "F.Fab")
			(effects
				(font
					(size 1.27 1.27)
				)
			)
		)
		(duplicate_pad_numbers_are_jumpers no)
		(fp_line
			(start -0.7874 -0.4064)
			(end 0.7874 -0.4064)
			(stroke
				(width 0.1524)
				(type default)
			)
			(layer "F.SilkS")
		)
		(fp_line
			(start -0.7874 0.4064)
			(end -0.7874 -0.4064)
			(stroke
				(width 0.1524)
				(type default)
			)
			(layer "F.SilkS")
		)
		(fp_line
			(start 0.7874 -0.4064)
			(end 0.7874 0.4064)
			(stroke
				(width 0.1524)
				(type default)
			)
			(layer "F.SilkS")
		)
		(fp_line
			(start 0.7874 0.4064)
			(end -0.7874 0.4064)
			(stroke
				(width 0.1524)
				(type default)
			)
			(layer "F.SilkS")
		)
		(fp_line
			(start -0.67945 -0.305054)
			(end -0.12065 -0.305054)
			(stroke
				(width 0.1)
				(type default)
			)
			(layer "F.Fab")
		)
		(fp_line
			(start -0.67945 0.3048)
			(end -0.67945 -0.305054)
			(stroke
				(width 0.1)
				(type default)
			)
			(layer "F.Fab")
		)
		(fp_line
			(start -0.12065 -0.305054)
			(end -0.12065 -0.2794)
			(stroke
				(width 0.1)
				(type default)
			)
			(layer "F.Fab")
		)
		(fp_line
			(start -0.12065 -0.2794)
			(end 0.12065 -0.2794)
			(stroke
				(width 0.1)
				(type default)
			)
			(layer "F.Fab")
		)
		(fp_line
			(start -0.12065 0.2794)
			(end -0.12065 0.3048)
			(stroke
				(width 0.1)
				(type default)
			)
			(layer "F.Fab")
		)
		(fp_line
			(start -0.12065 0.3048)
			(end -0.67945 0.3048)
			(stroke
				(width 0.1)
				(type default)
			)
			(layer "F.Fab")
		)
		(fp_line
			(start 0.120396 0.2794)
			(end -0.12065 0.2794)
			(stroke
				(width 0.1)
				(type default)
			)
			(layer "F.Fab")
		)
		(fp_line
			(start 0.120396 0.3048)
			(end 0.120396 0.2794)
			(stroke
				(width 0.1)
				(type default)
			)
			(layer "F.Fab")
		)
		(fp_line
			(start 0.12065 -0.3048)
			(end 0.67945 -0.3048)
			(stroke
				(width 0.1)
				(type default)
			)
			(layer "F.Fab")
		)
		(fp_line
			(start 0.12065 -0.2794)
			(end 0.12065 -0.3048)
			(stroke
				(width 0.1)
				(type default)
			)
			(layer "F.Fab")
		)
		(fp_line
			(start 0.67945 -0.3048)
			(end 0.67945 0.3048)
			(stroke
				(width 0.1)
				(type default)
			)
			(layer "F.Fab")
		)
		(fp_line
			(start 0.67945 0.3048)
			(end 0.120396 0.3048)
			(stroke
				(width 0.1)
				(type default)
			)
			(layer "F.Fab")
		)
		(pad "1" smd circle
			(at -0.40005 0)
			(size 0 0)
			(layers "F.Cu" "F.Mask" "F.Paste")
			(net "P3V3_AUX")
		)
		(pad "2" smd circle
			(at 0.40005 0)
			(size 0 0)
			(layers "F.Cu" "F.Mask" "F.Paste")
			(net "HP_LVC3_OCP_V3_2_PRSNT2")
		)
	)
	(footprint ""
		(layer "F.Cu")
		(at 283.310076 -412.579058 -90)
		(property "Reference" "C2328"
			(at 0 0 270)
			(layer "F.SilkS")
			(hide yes)
			(effects
				(font
					(size 1.27 1.27)
				)
			)
		)
		(property "Value" ""
			(at 0 0 270)
			(layer "F.Fab")
			(effects
				(font
					(size 1.27 1.27)
				)
			)
		)
		(duplicate_pad_numbers_are_jumpers no)
		(fp_line
			(start -0.7874 0.4064)
			(end -0.7874 -0.4064)
			(stroke
				(width 0.1524)
				(type default)
			)
			(layer "F.SilkS")
		)
		(fp_line
			(start 0.7874 0.4064)
			(end -0.7874 0.4064)
			(stroke
				(width 0.1524)
				(type default)
			)
			(layer "F.SilkS")
		)
		(fp_line
			(start -0.7874 -0.4064)
			(end 0.7874 -0.4064)
			(stroke
				(width 0.1524)
				(type default)
			)
			(layer "F.SilkS")
		)
		(fp_line
			(start 0.7874 -0.4064)
			(end 0.7874 0.4064)
			(stroke
				(width 0.1524)
				(type default)
			)
			(layer "F.SilkS")
		)
		(fp_line
			(start -0.67945 0.3048)
			(end -0.67945 -0.305054)
			(stroke
				(width 0.1)
				(type default)
			)
			(layer "F.Fab")
		)
		(fp_line
			(start -0.12065 0.3048)
			(end -0.67945 0.3048)
			(stroke
				(width 0.1)
				(type default)
			)
			(layer "F.Fab")
		)
		(fp_line
			(start 0.120396 0.3048)
			(end 0.120396 0.2794)
			(stroke
				(width 0.1)
				(type default)
			)
			(layer "F.Fab")
		)
		(fp_line
			(start 0.67945 0.3048)
			(end 0.120396 0.3048)
			(stroke
				(width 0.1)
				(type default)
			)
			(layer "F.Fab")
		)
		(fp_line
			(start -0.12065 0.2794)
			(end -0.12065 0.3048)
			(stroke
				(width 0.1)
				(type default)
			)
			(layer "F.Fab")
		)
		(fp_line
			(start 0.120396 0.2794)
			(end -0.12065 0.2794)
			(stroke
				(width 0.1)
				(type default)
			)
			(layer "F.Fab")
		)
		(fp_line
			(start -0.12065 -0.2794)
			(end 0.12065 -0.2794)
			(stroke
				(width 0.1)
				(type default)
			)
			(layer "F.Fab")
		)
		(fp_line
			(start 0.12065 -0.2794)
			(end 0.12065 -0.3048)
			(stroke
				(width 0.1)
				(type default)
			)
			(layer "F.Fab")
		)
		(fp_line
			(start 0.12065 -0.3048)
			(end 0.67945 -0.3048)
			(stroke
				(width 0.1)
				(type default)
			)
			(layer "F.Fab")
		)
		(fp_line
			(start 0.67945 -0.3048)
			(end 0.67945 0.3048)
			(stroke
				(width 0.1)
				(type default)
			)
			(layer "F.Fab")
		)
		(fp_line
			(start -0.67945 -0.305054)
			(end -0.12065 -0.305054)
			(stroke
				(width 0.1)
				(type default)
			)
			(layer "F.Fab")
		)
		(fp_line
			(start -0.12065 -0.305054)
			(end -0.12065 -0.2794)
			(stroke
				(width 0.1)
				(type default)
			)
			(layer "F.Fab")
		)
		(pad "1" smd circle
			(at -0.40005 0 270)
			(size 0 0)
			(layers "F.Cu" "F.Mask" "F.Paste")
			(net "P3V3_9ZXL045_P0_VDD")
		)
		(pad "2" smd circle
			(at 0.40005 0 270)
			(size 0 0)
			(layers "F.Cu" "F.Mask" "F.Paste")
			(net "GND")
		)
	)
)
